# T6G (Grand Teton) — schematic netlist excerpt (pin names and nets, part order shuffled) for the footprints in the layout excerpt that follows; sources: Cadence DE-HDL packaged netlist, KiCad conversion of 04192023_DAF0TMB3IC0_F0TG_MB_C_brd_V02_OCP.brd

R6705  Q_RES  0 5% CHIP  pkg 0603LF  page 323 : A = P0V9_CPU1_RT0_2A_2D ; B = P0V9_CPU1_RT0_2A
R8091  Q_RES  10K 1% EMPTY  pkg 0402LF  page 104 : A = P3V3_AUX ; B = PWRGD_CHGL_CPU1_R1

(kicad_pcb
	(version 20260206)
	(generator "pcbnew")
	(generator_version "10.0")
	(general
		(thickness 1.6)
		(legacy_teardrops no)
	)
	(paper "A4")
	(title_block
		(title "04192023_DAF0TMB3IC0_F0TG_MB_C_brd_V02_OCP.brd")
		(comment 1 "Grand Teton / footprints 408-409 of 8354")
	)
	(layers
		(0 "F.Cu" signal "TOP")
		(4 "In1.Cu" signal "GND")
		(6 "In2.Cu" signal "IN1")
		(8 "In3.Cu" signal "GND1")
		(10 "In4.Cu" signal "IN2")
		(12 "In5.Cu" signal "GND2")
		(14 "In6.Cu" signal "IN3")
		(16 "In7.Cu" signal "GND3")
		(18 "In8.Cu" signal "VCC")
		(20 "In9.Cu" signal "VCC1")
		(22 "In10.Cu" signal "GND4")
		(24 "In11.Cu" signal "IN4")
		(26 "In12.Cu" signal "GND5")
		(28 "In13.Cu" signal "IN5")
		(30 "In14.Cu" signal "GND6")
		(32 "In15.Cu" signal "IN6")
		(34 "In16.Cu" signal "GND7")
		(2 "B.Cu" signal "BOTTOM")
		(9 "F.Adhes" user "F.Adhesive")
		(11 "B.Adhes" user "B.Adhesive")
		(13 "F.Paste" user "Package Geometry/Pastemask Top")
		(15 "B.Paste" user "Package Geometry/Pastemask Bottom")
		(5 "F.SilkS" user "Ref Des/Silkscreen Top")
		(7 "B.SilkS" user "Ref Des/Silkscreen Bottom")
		(1 "F.Mask" user "Board Geometry/Soldermask Top")
		(3 "B.Mask" user "Board Geometry/Soldermask Bottom")
		(17 "Dwgs.User" user "User.Drawings")
		(19 "Cmts.User" user "User.Comments")
		(21 "Eco1.User" user "User.Eco1")
		(23 "Eco2.User" user "User.Eco2")
		(25 "Edge.Cuts" user "Board Geometry/Outline")
		(27 "Margin" user)
		(31 "F.CrtYd" user "Package Geometry/Place Bound Top")
		(29 "B.CrtYd" user "Package Geometry/Place Bound Bottom")
		(35 "F.Fab" user "Ref Des/Assembly Top")
		(33 "B.Fab" user "Ref Des/Assembly Bottom")
	)
	(footprint ""
		(layer "F.Cu")
		(at 198.247 -94.234)
		(property "Reference" "R8091"
			(at 0 0 0)
			(layer "F.SilkS")
			(hide yes)
			(effects
				(font
					(size 1.27 1.27)
				)
			)
		)
		(property "Value" ""
			(at 0 0 0)
			(layer "F.Fab")
			(effects
				(font
					(size 1.27 1.27)
				)
			)
		)
		(duplicate_pad_numbers_are_jumpers no)
		(fp_line
			(start -0.7874 -0.4064)
			(end 0.7874 -0.4064)
			(stroke
				(width 0.1524)
				(type default)
			)
			(layer "F.SilkS")
		)
		(fp_line
			(start -0.7874 0.4064)
			(end -0.7874 -0.4064)
			(stroke
				(width 0.1524)
				(type default)
			)
			(layer "F.SilkS")
		)
		(fp_line
			(start 0.7874 -0.4064)
			(end 0.7874 0.4064)
			(stroke
				(width 0.1524)
				(type default)
			)
			(layer "F.SilkS")
		)
		(fp_line
			(start 0.7874 0.4064)
			(end -0.7874 0.4064)
			(stroke
				(width 0.1524)
				(type default)
			)
			(layer "F.SilkS")
		)
		(fp_line
			(start -0.67945 -0.305054)
			(end -0.12065 -0.305054)
			(stroke
				(width 0.1)
				(type default)
			)
			(layer "F.Fab")
		)
		(fp_line
			(start -0.67945 0.3048)
			(end -0.67945 -0.305054)
			(stroke
				(width 0.1)
				(type default)
			)
			(layer "F.Fab")
		)
		(fp_line
			(start -0.12065 -0.305054)
			(end -0.12065 -0.2794)
			(stroke
				(width 0.1)
				(type default)
			)
			(layer "F.Fab")
		)
		(fp_line
			(start -0.12065 -0.2794)
			(end 0.12065 -0.2794)
			(stroke
				(width 0.1)
				(type default)
			)
			(layer "F.Fab")
		)
		(fp_line
			(start -0.12065 0.2794)
			(end -0.12065 0.3048)
			(stroke
				(width 0.1)
				(type default)
			)
			(layer "F.Fab")
		)
		(fp_line
			(start -0.12065 0.3048)
			(end -0.67945 0.3048)
			(stroke
				(width 0.1)
				(type default)
			)
			(layer "F.Fab")
		)
		(fp_line
			(start 0.120396 0.2794)
			(end -0.12065 0.2794)
			(stroke
				(width 0.1)
				(type default)
			)
			(layer "F.Fab")
		)
		(fp_line
			(start 0.120396 0.3048)
			(end 0.120396 0.2794)
			(stroke
				(width 0.1)
				(type default)
			)
			(layer "F.Fab")
		)
		(fp_line
			(start 0.12065 -0.3048)
			(end 0.67945 -0.3048)
			(stroke
				(width 0.1)
				(type default)
			)
			(layer "F.Fab")
		)
		(fp_line
			(start 0.12065 -0.2794)
			(end 0.12065 -0.3048)
			(stroke
				(width 0.1)
				(type default)
			)
			(layer "F.Fab")
		)
		(fp_line
			(start 0.67945 -0.3048)
			(end 0.67945 0.3048)
			(stroke
				(width 0.1)
				(type default)
			)
			(layer "F.Fab")
		)
		(fp_line
			(start 0.67945 0.3048)
			(end 0.120396 0.3048)
			(stroke
				(width 0.1)
				(type default)
			)
			(layer "F.Fab")
		)
		(pad "1" smd circle
			(at -0.40005 0)
			(size 0 0)
			(layers "F.Cu" "F.Mask" "F.Paste")
			(net "P3V3_AUX")
		)
		(pad "2" smd circle
			(at 0.40005 0)
			(size 0 0)
			(layers "F.Cu" "F.Mask" "F.Paste")
			(net "PWRGD_CHGL_CPU1_R1")
		)
	)
	(footprint ""
		(layer "F.Cu")
		(at 46.096428 -399.41246)
		(property "Reference" "R6705"
			(at 0 0 0)
			(layer "F.SilkS")
			(hide yes)
			(effects
				(font
					(size 1.27 1.27)
				)
			)
		)
		(property "Value" ""
			(at 0 0 0)
			(layer "F.Fab")
			(effects
				(font
					(size 1.27 1.27)
				)
			)
		)
		(duplicate_pad_numbers_are_jumpers no)
		(fp_line
			(start -1.2954 -0.5842)
			(end 1.2954 -0.5842)
			(stroke
				(width 0.1524)
				(type default)
			)
			(layer "F.SilkS")
		)
		(fp_line
			(start -1.2954 0.5842)
			(end -1.2954 -0.5842)
			(stroke
				(width 0.1524)
				(type default)
			)
			(layer "F.SilkS")
		)
		(fp_line
			(start 1.2954 -0.5842)
			(end 1.2954 0.5842)
			(stroke
				(width 0.1524)
				(type default)
			)
			(layer "F.SilkS")
		)
		(fp_line
			(start 1.2954 0.5842)
			(end -1.2954 0.5842)
			(stroke
				(width 0.1524)
				(type default)
			)
			(layer "F.SilkS")
		)
		(fp_line
			(start -1.1938 -0.406654)
			(end -0.8636 -0.406654)
			(stroke
				(width 0.1)
				(type default)
			)
			(layer "F.Fab")
		)
		(fp_line
			(start -1.1938 0.4064)
			(end -1.1938 -0.406654)
			(stroke
				(width 0.1)
				(type default)
			)
			(layer "F.Fab")
		)
		(fp_line
			(start -0.8636 -0.4572)
			(end 0.8636 -0.4572)
			(stroke
				(width 0.1)
				(type default)
			)
			(layer "F.Fab")
		)
		(fp_line
			(start -0.8636 -0.406654)
			(end -0.8636 -0.4572)
			(stroke
				(width 0.1)
				(type default)
			)
			(layer "F.Fab")
		)
		(fp_line
			(start -0.8636 0.4064)
			(end -1.1938 0.4064)
			(stroke
				(width 0.1)
				(type default)
			)
			(layer "F.Fab")
		)
		(fp_line
			(start -0.8636 0.4318)
			(end -0.8636 0.4064)
			(stroke
				(width 0.1)
				(type default)
			)
			(layer "F.Fab")
		)
		(fp_line
			(start -0.8636 0.4572)
			(end -0.8636 0.4318)
			(stroke
				(width 0.1)
				(type default)
			)
			(layer "F.Fab")
		)
		(fp_line
			(start 0.8636 -0.4572)
			(end 0.8636 -0.406654)
			(stroke
				(width 0.1)
				(type default)
			)
			(layer "F.Fab")
		)
		(fp_line
			(start 0.8636 -0.406654)
			(end 1.1938 -0.406654)
			(stroke
				(width 0.1)
				(type default)
			)
			(layer "F.Fab")
		)
		(fp_line
			(start 0.8636 0.4064)
			(end 0.8636 0.4572)
			(stroke
				(width 0.1)
				(type default)
			)
			(layer "F.Fab")
		)
		(fp_line
			(start 0.8636 0.4572)
			(end -0.8636 0.4572)
			(stroke
				(width 0.1)
				(type default)
			)
			(layer "F.Fab")
		)
		(fp_line
			(start 1.1938 -0.406654)
			(end 1.1938 0.4064)
			(stroke
				(width 0.1)
				(type default)
			)
			(layer "F.Fab")
		)
		(fp_line
			(start 1.1938 0.4064)
			(end 0.8636 0.4064)
			(stroke
				(width 0.1)
				(type default)
			)
			(layer "F.Fab")
		)
		(pad "1" smd rect
			(at -0.7366 0 270)
			(size 0.7112 0.8128)
			(layers "F.Cu" "F.Mask" "F.Paste")
			(net "P0V9_CPU1_RT0_2A_2D")
		)
		(pad "2" smd rect
			(at 0.7366 0 270)
			(size 0.7112 0.8128)
			(layers "F.Cu" "F.Mask" "F.Paste")
			(net "P0V9_CPU1_RT0_2A")
		)
	)
)
